FILE_TYPE = CONNECTIVITY;
{Allegro Design Entry HDL 17.2-2016 S081 (4005846) 1/11/2022}
"PAGE_NUMBER" = 95;
0"NC";
1"P3V3_AUX\g";
2"P12V_S3_AUX_CPU0_NVDIMM\g";
3"P12V_S3_AUX_CPU0_NVDIMM\g";
4"P3V3_AUX\g";
5"GND\g";
6"GND\g";
7"GND\g";
8"GND\g";
9"GND\g";
10"M_G_CPU0_SA_DQ<31:0>";
11"M_G_CPU0_SA_CB<7:0>";
12"M_G_CPU0_SB_CB<7:0>";
13"M_G_CPU0_SA_CA<6:0>";
14"M_G_CPU0_SB_CA<6:0>";
15"M_G_CPU0_SB_DQ<31:0>";
16"M_G_CPU0_SA_DQS_DP<9:0>";
17"M_G_CPU0_SB_DQS_DP<9:0>";
18"M_G_CPU0_SA_DQS_DN<9:0>";
19"M_G_CPU0_SB_DQS_DN<9:0>";
20"PD_CHG_CPU0_DIMM2_SAA";
21"I3C_SPD_DDREFGH_CPU0_LVC1_SDA";
22"M_G_CPU0_ALERT_N";
23"RST_M_GH_CPU0_FPGA_N";
24"I3C_SPD_DDREFGH_CPU0_LVC1_SCL_R6";
25"I3C_SPD_DDREFGH_CPU0_LVC1_SCL";
26"PWRGD_CHG_CPU0_DIMM2";
27"TP_CHG_CPU0_DIMM2_FRU_4";
28"TP_CHG_CPU0_DIMM2_FRU_3";
29"TP_CHG_CPU0_DIMM2_FRU_0";
30"TP_CHG_CPU0_DIMM2_FRU_5";
31"TP_CHG_CPU0_DIMM2_FRU_2";
32"TP_CHG_CPU0_DIMM2_FRU_1";
33"M_G_CPU0_SB_DQS_DP<2>";
34"M_G_CPU0_SB_DQS_DN<0>";
35"M_G_CPU0_SB_DQS_DN<2>";
36"M_G_CPU0_SB_DQS_DN<1>";
37"M_G_CPU0_SB_DQS_DN<3>";
38"M_G_CPU0_SB_DQS_DN<4>";
39"M_G_CPU0_SB_DQS_DN<5>";
40"M_G_CPU0_SB_DQS_DN<6>";
41"M_G_CPU0_SB_DQS_DN<7>";
42"M_G_CPU0_SB_DQS_DN<8>";
43"M_G_CPU0_SB_DQS_DN<9>";
44"M_G_CPU0_SA_DQS_DN<0>";
45"M_G_CPU0_SA_DQS_DN<1>";
46"M_G_CPU0_SA_DQS_DN<2>";
47"M_G_CPU0_SA_DQS_DN<3>";
48"M_G_CPU0_SA_DQS_DN<4>";
49"M_G_CPU0_SA_DQS_DN<5>";
50"M_G_CPU0_SA_DQS_DN<6>";
51"M_G_CPU0_SA_DQS_DN<7>";
52"M_G_CPU0_SA_DQS_DN<8>";
53"M_G_CPU0_SA_DQS_DN<9>";
54"M_G_CPU0_SB_DQS_DP<1>";
55"M_G_CPU0_SB_DQS_DP<0>";
56"M_G_CPU0_SB_DQS_DP<3>";
57"M_G_CPU0_SB_DQS_DP<4>";
58"M_G_CPU0_SB_DQS_DP<5>";
59"M_G_CPU0_SB_DQS_DP<6>";
60"M_G_CPU0_SB_DQS_DP<7>";
61"M_G_CPU0_SB_DQS_DP<8>";
62"M_G_CPU0_SB_DQS_DP<9>";
63"M_G_CPU0_SA_DQS_DP<1>";
64"M_G_CPU0_SA_DQS_DP<0>";
65"M_G_CPU0_SA_DQS_DP<2>";
66"M_G_CPU0_SA_DQS_DP<3>";
67"M_G_CPU0_SA_DQS_DP<4>";
68"M_G_CPU0_SA_DQS_DP<5>";
69"M_G_CPU0_SA_DQS_DP<6>";
70"M_G_CPU0_SA_DQS_DP<7>";
71"M_G_CPU0_SA_DQS_DP<8>";
72"M_G_CPU0_SA_DQS_DP<9>";
73"TP_CHG_CPU0_DIMM2_FRU_6";
74"M_G_CPU0_SA_DQ<16>";
75"M_G_CPU0_SA_DQ<14>";
76"M_G_CPU0_SA_DQ<21>";
77"M_G_CPU0_SB_DQ<28>";
78"M_G_CPU0_SB_DQ<15>";
79"M_G_CPU0_SB_PAR";
80"M_G_CPU0_SA_PAR";
81"M_G_CPU0_SB_RSP<1>";
82"M_G_CPU0_SA_RSP<1>";
83"M_G_CPU0_SB_DQ<0>";
84"M_G_CPU0_SB_DQ<1>";
85"M_G_CPU0_SB_DQ<2>";
86"M_G_CPU0_SB_DQ<3>";
87"M_G_CPU0_SB_DQ<4>";
88"M_G_CPU0_SB_DQ<5>";
89"M_G_CPU0_SB_DQ<6>";
90"M_G_CPU0_SB_DQ<7>";
91"M_G_CPU0_SB_DQ<8>";
92"M_G_CPU0_SB_DQ<9>";
93"M_G_CPU0_SB_DQ<10>";
94"M_G_CPU0_SB_DQ<11>";
95"M_G_CPU0_SB_DQ<12>";
96"M_G_CPU0_SB_DQ<13>";
97"M_G_CPU0_SB_DQ<14>";
98"M_G_CPU0_SB_DQ<16>";
99"M_G_CPU0_SB_DQ<17>";
100"M_G_CPU0_SB_DQ<18>";
101"M_G_CPU0_SB_DQ<19>";
102"M_G_CPU0_SB_DQ<20>";
103"M_G_CPU0_SB_DQ<21>";
104"M_G_CPU0_SB_DQ<22>";
105"M_G_CPU0_SB_DQ<23>";
106"M_G_CPU0_SB_DQ<24>";
107"M_G_CPU0_SB_DQ<25>";
108"M_G_CPU0_SB_DQ<26>";
109"M_G_CPU0_SB_DQ<27>";
110"M_G_CPU0_SB_DQ<29>";
111"M_G_CPU0_SB_DQ<30>";
112"M_G_CPU0_SB_DQ<31>";
113"M_G_CPU0_SA_DQ<0>";
114"M_G_CPU0_SA_DQ<1>";
115"M_G_CPU0_SA_DQ<2>";
116"M_G_CPU0_SA_DQ<3>";
117"M_G_CPU0_SA_DQ<4>";
118"M_G_CPU0_SA_DQ<5>";
119"M_G_CPU0_SA_DQ<6>";
120"M_G_CPU0_SA_DQ<7>";
121"M_G_CPU0_SA_DQ<8>";
122"M_G_CPU0_SA_DQ<9>";
123"M_G_CPU0_SA_DQ<10>";
124"M_G_CPU0_SA_DQ<11>";
125"M_G_CPU0_SA_DQ<12>";
126"M_G_CPU0_SA_DQ<13>";
127"M_G_CPU0_SA_DQ<15>";
128"M_G_CPU0_SA_DQ<17>";
129"M_G_CPU0_SA_DQ<18>";
130"M_G_CPU0_SA_DQ<19>";
131"M_G_CPU0_SA_DQ<20>";
132"M_G_CPU0_SA_DQ<22>";
133"M_G_CPU0_SA_DQ<23>";
134"M_G_CPU0_SA_DQ<24>";
135"M_G_CPU0_SA_DQ<25>";
136"M_G_CPU0_SA_DQ<26>";
137"M_G_CPU0_SA_DQ<27>";
138"M_G_CPU0_SA_DQ<28>";
139"M_G_CPU0_SA_DQ<29>";
140"M_G_CPU0_SA_DQ<30>";
141"M_G_CPU0_SB_CS_N<3>";
142"M_G_CPU0_SA_CS_N<3>";
143"M_G_CPU0_SB_CS_N<2>";
144"M_G_CPU0_SA_CS_N<2>";
145"M_G_CPU0_CLK_DP<1>";
146"M_G_CPU0_CLK_DN<1>";
147"M_G_CPU0_SB_CB<0>";
148"M_G_CPU0_SB_CB<1>";
149"M_G_CPU0_SB_CB<2>";
150"M_G_CPU0_SB_CB<3>";
151"M_G_CPU0_SB_CB<4>";
152"M_G_CPU0_SB_CB<5>";
153"M_G_CPU0_SB_CB<6>";
154"M_G_CPU0_SA_CB<0>";
155"M_G_CPU0_SA_CB<2>";
156"M_G_CPU0_SA_CB<3>";
157"M_G_CPU0_SA_CB<5>";
158"M_G_CPU0_SA_CB<6>";
159"M_G_CPU0_SB_CA<6>";
160"M_G_CPU0_SA_CA<6>";
161"M_G_CPU0_SB_CA<5>";
162"M_G_CPU0_SA_CA<5>";
163"M_G_CPU0_SB_CA<4>";
164"M_G_CPU0_SA_CA<4>";
165"M_G_CPU0_SB_CA<3>";
166"M_G_CPU0_SA_CA<3>";
167"M_G_CPU0_SB_CA<2>";
168"M_G_CPU0_SA_CA<2>";
169"M_G_CPU0_SB_CA<1>";
170"M_G_CPU0_SA_CA<1>";
171"M_G_CPU0_SB_CA<0>";
172"M_G_CPU0_SA_CA<0>";
173"M_G_CPU0_SB_CB<7>";
174"M_G_CPU0_SA_CB<1>";
175"M_G_CPU0_SA_CB<4>";
176"M_G_CPU0_SA_CB<7>";
177"M_G_CPU0_SA_DQ<31>";
178"PD_CHG_CPU0_DIMM2_SAA";
%"TAP"
"1","(600,2825)","0","standard","I100";
;
CDS_LIB"standard"
BODY_TYPE"PLUMBING"
HDL_TAP"TRUE";
"B \NAC \NWC"10;
"S \NAC"
BN"21"76;
%"TAP"
"1","(600,2775)","0","standard","I101";
;
CDS_LIB"standard"
BODY_TYPE"PLUMBING"
HDL_TAP"TRUE";
"B \NAC \NWC"10;
"S \NAC"
BN"20"131;
%"TAP"
"1","(600,2875)","0","standard","I102";
;
CDS_LIB"standard"
BODY_TYPE"PLUMBING"
HDL_TAP"TRUE";
"B \NAC \NWC"10;
"S \NAC"
BN"22"132;
%"TAP"
"1","(600,2925)","0","standard","I103";
;
CDS_LIB"standard"
BODY_TYPE"PLUMBING"
HDL_TAP"TRUE";
"B \NAC \NWC"10;
"S \NAC"
BN"23"133;
%"TAP"
"1","(600,2975)","0","standard","I104";
;
CDS_LIB"standard"
BODY_TYPE"PLUMBING"
HDL_TAP"TRUE";
"B \NAC \NWC"10;
"S \NAC"
BN"24"134;
%"TAP"
"1","(-1050,3075)","2","standard","I106";
;
CDS_LIB"standard"
BODY_TYPE"PLUMBING"
HDL_TAP"TRUE";
"B \NAC \NWC"13;
"S \NAC"
BN"1"170;
%"TAP"
"1","(-1050,3025)","2","standard","I107";
;
CDS_LIB"standard"
BODY_TYPE"PLUMBING"
HDL_TAP"TRUE";
"B \NAC \NWC"13;
"S \NAC"
BN"0"172;
%"TAP"
"1","(-1050,3125)","2","standard","I108";
;
CDS_LIB"standard"
BODY_TYPE"PLUMBING"
HDL_TAP"TRUE";
"B \NAC \NWC"13;
"S \NAC"
BN"2"168;
%"TAP"
"1","(-1050,3225)","2","standard","I109";
;
CDS_LIB"standard"
BODY_TYPE"PLUMBING"
HDL_TAP"TRUE";
"B \NAC \NWC"13;
"S \NAC"
BN"4"164;
%"TAP"
"1","(-1050,3175)","2","standard","I110";
;
CDS_LIB"standard"
BODY_TYPE"PLUMBING"
HDL_TAP"TRUE";
"B \NAC \NWC"13;
"S \NAC"
BN"3"166;
%"TAP"
"1","(-1050,3325)","2","standard","I111";
;
CDS_LIB"standard"
BODY_TYPE"PLUMBING"
HDL_TAP"TRUE";
"B \NAC \NWC"13;
"S \NAC"
BN"6"160;
%"TAP"
"1","(-1050,3275)","2","standard","I112";
;
CDS_LIB"standard"
BODY_TYPE"PLUMBING"
HDL_TAP"TRUE";
"B \NAC \NWC"13;
"S \NAC"
BN"5"162;
%"TAP"
"1","(600,3075)","0","standard","I113";
;
CDS_LIB"standard"
BODY_TYPE"PLUMBING"
HDL_TAP"TRUE";
"B \NAC \NWC"10;
"S \NAC"
BN"26"136;
%"TAP"
"1","(600,3025)","0","standard","I114";
;
CDS_LIB"standard"
BODY_TYPE"PLUMBING"
HDL_TAP"TRUE";
"B \NAC \NWC"10;
"S \NAC"
BN"25"135;
%"TAP"
"1","(600,3175)","0","standard","I115";
;
CDS_LIB"standard"
BODY_TYPE"PLUMBING"
HDL_TAP"TRUE";
"B \NAC \NWC"10;
"S \NAC"
BN"28"138;
%"TAP"
"1","(600,3225)","0","standard","I116";
;
CDS_LIB"standard"
BODY_TYPE"PLUMBING"
HDL_TAP"TRUE";
"B \NAC \NWC"10;
"S \NAC"
BN"29"139;
%"TAP"
"1","(600,3125)","0","standard","I117";
;
CDS_LIB"standard"
BODY_TYPE"PLUMBING"
HDL_TAP"TRUE";
"B \NAC \NWC"10;
"S \NAC"
BN"27"137;
%"TAP"
"1","(600,3275)","0","standard","I118";
;
CDS_LIB"standard"
BODY_TYPE"PLUMBING"
HDL_TAP"TRUE";
"B \NAC \NWC"10;
"S \NAC"
BN"30"140;
%"TAP"
"1","(600,3325)","0","standard","I119";
;
CDS_LIB"standard"
BODY_TYPE"PLUMBING"
HDL_TAP"TRUE";
"B \NAC \NWC"10;
"S \NAC"
BN"31"177;
%"UNIVERSAL_GND"
"1","(2325,-925)","0","logical_power","I120";
;
CDS_LIB"logical_power"
HDL_POWER"GND";
"A"9;
%"Q_CAP"
"1","(2325,-550)","0","pure_quanta","I121";
;
PART_NUMBER"CH5221MEB00"
MATERIAL"X6S"
TOLERANCE"20%"
VOLTAGE"6.3V"
VALUE"2.2UF"
PACK_TYPE"C0402"
$LOCATION"C41"
CDS_LIB"pure_quanta"
CDS_LOCATION"C41"
$SEC"1"
CDS_SEC"1";
"B"
$PN"2"9;
"A"
$PN"1"4;
%"VCC_CORE"
"1","(2325,-225)","0","logical_power","I122";
;
HDL_POWER"P3V3_AUX"
CDS_LIB"logical_power";
"A"4;
%"Q_CAP"
"1","(3325,-550)","0","pure_quanta","I125";
;
PART_NUMBER"CH6103KEA00"
TOLERANCE"10%"
VOLTAGE"16V"
VALUE"10UF"
PACK_TYPE"C0805"
MATERIAL"X6S"
$LOCATION"C42"
CDS_LIB"pure_quanta"
CDS_LOCATION"C42"
$SEC"1"
CDS_SEC"1";
"B"
$PN"2"8;
"A"
$PN"1"3;
%"VCC_CORE"
"1","(3325,-225)","0","logical_power","I126";
;
HDL_POWER"P12V_S3_AUX_CPU0_NVDIMM"
CDS_LIB"logical_power";
"A"3;
%"UNIVERSAL_GND"
"1","(3950,-925)","0","logical_power","I127";
;
CDS_LIB"logical_power"
HDL_POWER"GND";
"A"8;
%"Q_CAP"
"1","(3950,-550)","0","pure_quanta","I128";
;
PART_NUMBER"CH6103KEA00"
TOLERANCE"10%"
VOLTAGE"16V"
VALUE"10UF"
PACK_TYPE"C0805"
MATERIAL"X6S"
$LOCATION"C43"
CDS_LIB"pure_quanta"
CDS_LOCATION"C43"
$SEC"1"
CDS_SEC"1";
"B"
$PN"2"8;
"A"
$PN"1"3;
%"UNIVERSAL_GND"
"1","(5025,-375)","0","logical_power","I129";
;
CDS_LIB"logical_power"
HDL_POWER"GND";
"A"7;
%"TAP"
"1","(3375,1375)","0","standard","I130";
;
CDS_LIB"standard"
BODY_TYPE"PLUMBING"
HDL_TAP"TRUE";
"B \NAC \NWC"17;
"S \NAC"
BN"0"55;
%"TAP"
"1","(3550,1325)","0","standard","I131";
;
CDS_LIB"standard"
BODY_TYPE"PLUMBING"
HDL_TAP"TRUE";
"B \NAC \NWC"19;
"S \NAC"
BN"0"34;
%"TAP"
"1","(3550,1425)","0","standard","I132";
;
CDS_LIB"standard"
BODY_TYPE"PLUMBING"
HDL_TAP"TRUE";
"B \NAC \NWC"19;
"S \NAC"
BN"1"36;
%"TAP"
"1","(3375,1475)","0","standard","I133";
;
CDS_LIB"standard"
BODY_TYPE"PLUMBING"
HDL_TAP"TRUE";
"B \NAC \NWC"17;
"S \NAC"
BN"1"54;
%"TAP"
"1","(3375,1575)","0","standard","I134";
;
CDS_LIB"standard"
BODY_TYPE"PLUMBING"
HDL_TAP"TRUE";
"B \NAC \NWC"17;
"S \NAC"
BN"2"33;
%"TAP"
"1","(3375,1675)","0","standard","I135";
;
CDS_LIB"standard"
BODY_TYPE"PLUMBING"
HDL_TAP"TRUE";
"B \NAC \NWC"17;
"S \NAC"
BN"3"56;
%"TAP"
"1","(3375,1775)","0","standard","I136";
;
CDS_LIB"standard"
BODY_TYPE"PLUMBING"
HDL_TAP"TRUE";
"B \NAC \NWC"17;
"S \NAC"
BN"4"57;
%"TAP"
"1","(3375,1875)","0","standard","I137";
;
CDS_LIB"standard"
BODY_TYPE"PLUMBING"
HDL_TAP"TRUE";
"B \NAC \NWC"17;
"S \NAC"
BN"5"58;
%"TAP"
"1","(3550,1525)","0","standard","I138";
;
CDS_LIB"standard"
BODY_TYPE"PLUMBING"
HDL_TAP"TRUE";
"B \NAC \NWC"19;
"S \NAC"
BN"2"35;
%"TAP"
"1","(3550,1625)","0","standard","I139";
;
CDS_LIB"standard"
BODY_TYPE"PLUMBING"
HDL_TAP"TRUE";
"B \NAC \NWC"19;
"S \NAC"
BN"3"37;
%"TAP"
"1","(3550,1725)","0","standard","I140";
;
CDS_LIB"standard"
BODY_TYPE"PLUMBING"
HDL_TAP"TRUE";
"B \NAC \NWC"19;
"S \NAC"
BN"4"38;
%"TAP"
"1","(3550,1825)","0","standard","I141";
;
CDS_LIB"standard"
BODY_TYPE"PLUMBING"
HDL_TAP"TRUE";
"B \NAC \NWC"19;
"S \NAC"
BN"5"39;
%"TAP"
"1","(3550,1925)","0","standard","I142";
;
CDS_LIB"standard"
BODY_TYPE"PLUMBING"
HDL_TAP"TRUE";
"B \NAC \NWC"19;
"S \NAC"
BN"6"40;
%"TAP"
"1","(3375,1975)","0","standard","I143";
;
CDS_LIB"standard"
BODY_TYPE"PLUMBING"
HDL_TAP"TRUE";
"B \NAC \NWC"17;
"S \NAC"
BN"6"59;
%"TAP"
"1","(3375,2075)","0","standard","I144";
;
CDS_LIB"standard"
BODY_TYPE"PLUMBING"
HDL_TAP"TRUE";
"B \NAC \NWC"17;
"S \NAC"
BN"7"60;
%"TAP"
"1","(3375,2175)","0","standard","I145";
;
CDS_LIB"standard"
BODY_TYPE"PLUMBING"
HDL_TAP"TRUE";
"B \NAC \NWC"17;
"S \NAC"
BN"8"61;
%"TAP"
"1","(3375,2275)","0","standard","I146";
;
CDS_LIB"standard"
BODY_TYPE"PLUMBING"
HDL_TAP"TRUE";
"B \NAC \NWC"17;
"S \NAC"
BN"9"62;
%"TAP"
"1","(3375,2425)","0","standard","I147";
;
CDS_LIB"standard"
BODY_TYPE"PLUMBING"
HDL_TAP"TRUE";
"B \NAC \NWC"16;
"S \NAC"
BN"0"64;
%"TAP"
"1","(3550,2025)","0","standard","I148";
;
CDS_LIB"standard"
BODY_TYPE"PLUMBING"
HDL_TAP"TRUE";
"B \NAC \NWC"19;
"S \NAC"
BN"7"41;
%"TAP"
"1","(3550,2225)","0","standard","I149";
;
CDS_LIB"standard"
BODY_TYPE"PLUMBING"
HDL_TAP"TRUE";
"B \NAC \NWC"19;
"S \NAC"
BN"9"43;
%"TAP"
"1","(3550,2125)","0","standard","I150";
;
CDS_LIB"standard"
BODY_TYPE"PLUMBING"
HDL_TAP"TRUE";
"B \NAC \NWC"19;
"S \NAC"
BN"8"42;
%"TAP"
"1","(3550,2375)","0","standard","I151";
;
CDS_LIB"standard"
BODY_TYPE"PLUMBING"
HDL_TAP"TRUE";
"B \NAC \NWC"18;
"S \NAC"
BN"0"44;
%"TAP"
"1","(3550,2475)","0","standard","I152";
;
CDS_LIB"standard"
BODY_TYPE"PLUMBING"
HDL_TAP"TRUE";
"B \NAC \NWC"18;
"S \NAC"
BN"1"45;
%"TAP"
"1","(3375,2525)","0","standard","I153";
;
CDS_LIB"standard"
BODY_TYPE"PLUMBING"
HDL_TAP"TRUE";
"B \NAC \NWC"16;
"S \NAC"
BN"1"63;
%"TAP"
"1","(3375,2725)","0","standard","I154";
;
CDS_LIB"standard"
BODY_TYPE"PLUMBING"
HDL_TAP"TRUE";
"B \NAC \NWC"16;
"S \NAC"
BN"3"66;
%"TAP"
"1","(3375,2625)","0","standard","I155";
;
CDS_LIB"standard"
BODY_TYPE"PLUMBING"
HDL_TAP"TRUE";
"B \NAC \NWC"16;
"S \NAC"
BN"2"65;
%"TAP"
"1","(3375,2825)","0","standard","I156";
;
CDS_LIB"standard"
BODY_TYPE"PLUMBING"
HDL_TAP"TRUE";
"B \NAC \NWC"16;
"S \NAC"
BN"4"67;
%"TAP"
"1","(3375,2925)","0","standard","I157";
;
CDS_LIB"standard"
BODY_TYPE"PLUMBING"
HDL_TAP"TRUE";
"B \NAC \NWC"16;
"S \NAC"
BN"5"68;
%"TAP"
"1","(3550,2575)","0","standard","I158";
;
CDS_LIB"standard"
BODY_TYPE"PLUMBING"
HDL_TAP"TRUE";
"B \NAC \NWC"18;
"S \NAC"
BN"2"46;
%"TAP"
"1","(3550,2675)","0","standard","I159";
;
CDS_LIB"standard"
BODY_TYPE"PLUMBING"
HDL_TAP"TRUE";
"B \NAC \NWC"18;
"S \NAC"
BN"3"47;
%"TAP"
"1","(3550,2775)","0","standard","I160";
;
CDS_LIB"standard"
BODY_TYPE"PLUMBING"
HDL_TAP"TRUE";
"B \NAC \NWC"18;
"S \NAC"
BN"4"48;
%"TAP"
"1","(3550,2975)","0","standard","I161";
;
CDS_LIB"standard"
BODY_TYPE"PLUMBING"
HDL_TAP"TRUE";
"B \NAC \NWC"18;
"S \NAC"
BN"6"50;
%"TAP"
"1","(3550,2875)","0","standard","I162";
;
CDS_LIB"standard"
BODY_TYPE"PLUMBING"
HDL_TAP"TRUE";
"B \NAC \NWC"18;
"S \NAC"
BN"5"49;
%"TAP"
"1","(3375,3025)","0","standard","I166";
;
CDS_LIB"standard"
BODY_TYPE"PLUMBING"
HDL_TAP"TRUE";
"B \NAC \NWC"16;
"S \NAC"
BN"6"69;
%"TAP"
"1","(3375,3225)","0","standard","I167";
;
CDS_LIB"standard"
BODY_TYPE"PLUMBING"
HDL_TAP"TRUE";
"B \NAC \NWC"16;
"S \NAC"
BN"8"71;
%"TAP"
"1","(3375,3125)","0","standard","I168";
;
CDS_LIB"standard"
BODY_TYPE"PLUMBING"
HDL_TAP"TRUE";
"B \NAC \NWC"16;
"S \NAC"
BN"7"70;
%"TAP"
"1","(3375,3325)","0","standard","I169";
;
CDS_LIB"standard"
BODY_TYPE"PLUMBING"
HDL_TAP"TRUE";
"B \NAC \NWC"16;
"S \NAC"
BN"9"72;
%"TAP"
"1","(3550,3075)","0","standard","I170";
;
CDS_LIB"standard"
BODY_TYPE"PLUMBING"
HDL_TAP"TRUE";
"B \NAC \NWC"18;
"S \NAC"
BN"7"51;
%"TAP"
"1","(3550,3175)","0","standard","I171";
;
CDS_LIB"standard"
BODY_TYPE"PLUMBING"
HDL_TAP"TRUE";
"B \NAC \NWC"18;
"S \NAC"
BN"8"52;
%"TAP"
"1","(3550,3275)","0","standard","I172";
;
CDS_LIB"standard"
BODY_TYPE"PLUMBING"
HDL_TAP"TRUE";
"B \NAC \NWC"18;
"S \NAC"
BN"9"53;
%"VCC_CORE"
"1","(5025,3875)","0","logical_power","I175";
;
HDL_POWER"P12V_S3_AUX_CPU0_NVDIMM"
CDS_LIB"logical_power";
"A"2;
%"SCONN288_ADR50017P087CC"
"3","(5875,1700)","0","pure_quanta","I176";
;
PART_NUMBER"DFHST8FS460"
PART_TYPE"SMLF"
VALUE"SCONN288_ADR50017-P087CC"
MATERIAL"IO"
$LOCATION"J14"
NEEDS_NO_SIZE"TRUE"
CDS_LMAN_SYM_OUTLINE"-450,1775,450,-1775"
CDS_LIB"pure_quanta"
CDS_LOCATION"J14"
$SEC"3"
CDS_SEC"3";
"G3"
$PN"G3"6;
"G2"
$PN"G2"6;
"G1"
$PN"G1"6;
"VSS62"
$PN"141"6;
"VSS61"
$PN"139"6;
"VSS60"
$PN"136"6;
"VSS58"
$PN"132"6;
"VSS104"
$PN"240"7;
"VSS102"
$PN"235"7;
"VSS100"
$PN"230"7;
"VIN_BULK2"
$PN"146"2;
"VIN_BULK1"
$PN"145"2;
"VIN_BULK0"
$PN"1"2;
"VSS126"
$PN"288"7;
"VSS125"
$PN"286"7;
"VSS124"
$PN"284"7;
"VSS123"
$PN"281"7;
"VSS122"
$PN"279"7;
"VSS121"
$PN"277"7;
"VSS120"
$PN"275"7;
"VSS119"
$PN"273"7;
"VSS118"
$PN"270"7;
"VSS117"
$PN"268"7;
"VSS116"
$PN"266"7;
"VSS115"
$PN"264"7;
"VSS114"
$PN"262"7;
"VSS113"
$PN"259"7;
"VSS112"
$PN"257"7;
"VSS111"
$PN"255"7;
"VSS110"
$PN"253"7;
"VSS109"
$PN"251"7;
"VSS108"
$PN"248"7;
"VSS107"
$PN"246"7;
"VSS106"
$PN"244"7;
"VSS105"
$PN"242"7;
"VSS103"
$PN"237"7;
"VSS101"
$PN"233"7;
"VSS99"
$PN"228"7;
"VSS98"
$PN"226"7;
"VSS97"
$PN"224"7;
"VSS96"
$PN"222"7;
"VSS95"
$PN"219"7;
"VSS94"
$PN"216"7;
"VSS93"
$PN"214"7;
"VSS92"
$PN"212"7;
"VSS91"
$PN"210"7;
"VSS90"
$PN"208"7;
"VSS89"
$PN"206"7;
"VSS88"
$PN"204"7;
"VSS87"
$PN"202"7;
"VSS86"
$PN"199"7;
"VSS85"
$PN"197"7;
"VSS84"
$PN"195"7;
"VSS83"
$PN"193"7;
"VSS82"
$PN"191"7;
"VSS81"
$PN"188"7;
"VSS80"
$PN"186"7;
"VSS79"
$PN"184"7;
"VSS78"
$PN"182"7;
"VSS77"
$PN"180"7;
"VSS76"
$PN"177"7;
"VSS75"
$PN"175"7;
"VSS74"
$PN"173"7;
"VSS73"
$PN"171"7;
"VSS72"
$PN"169"7;
"VSS71"
$PN"166"7;
"VSS70"
$PN"164"7;
"VSS69"
$PN"162"7;
"VSS68"
$PN"160"7;
"VSS67"
$PN"158"7;
"VSS66"
$PN"155"7;
"VSS65"
$PN"153"7;
"VSS64"
$PN"151"7;
"VSS63"
$PN"143"6;
"VSS59"
$PN"134"6;
"VSS57"
$PN"130"6;
"VSS56"
$PN"128"6;
"VSS55"
$PN"125"6;
"VSS54"
$PN"123"6;
"VSS53"
$PN"121"6;
"VSS52"
$PN"119"6;
"VSS51"
$PN"117"6;
"VSS50"
$PN"114"6;
"VSS49"
$PN"112"6;
"VSS48"
$PN"110"6;
"VSS47"
$PN"108"6;
"VSS46"
$PN"106"6;
"VSS45"
$PN"103"6;
"VSS44"
$PN"101"6;
"VSS43"
$PN"99"6;
"VSS42"
$PN"97"6;
"VSS41"
$PN"95"6;
"VSS40"
$PN"92"6;
"VSS39"
$PN"90"6;
"VSS38"
$PN"88"6;
"VSS37"
$PN"85"6;
"VSS36"
$PN"83"6;
"VSS35"
$PN"81"6;
"VSS34"
$PN"79"6;
"VSS33"
$PN"77"6;
"VSS32"
$PN"75"6;
"VSS31"
$PN"73"6;
"VSS30"
$PN"71"6;
"VSS29"
$PN"69"6;
"VSS28"
$PN"67"6;
"VSS27"
$PN"65"6;
"VSS26"
$PN"63"6;
"VSS25"
$PN"61"6;
"VSS24"
$PN"59"6;
"VSS23"
$PN"57"6;
"VSS22"
$PN"54"6;
"VSS21"
$PN"52"6;
"VSS20"
$PN"50"6;
"VSS19"
$PN"48"6;
"VSS18"
$PN"46"6;
"VSS17"
$PN"43"6;
"VSS16"
$PN"41"6;
"VSS15"
$PN"39"6;
"VSS14"
$PN"37"6;
"VSS13"
$PN"35"6;
"VSS12"
$PN"32"6;
"VSS11"
$PN"30"6;
"VSS10"
$PN"28"6;
"VSS9"
$PN"26"6;
"VSS8"
$PN"24"6;
"VSS7"
$PN"21"6;
"VSS6"
$PN"19"6;
"VSS5"
$PN"17"6;
"VSS4"
$PN"15"6;
"VSS3"
$PN"13"6;
"VSS2"
$PN"10"6;
"VSS1"
$PN"8"6;
"VSS0"
$PN"6"6;
%"UNIVERSAL_GND"
"1","(6725,-375)","0","logical_power","I177";
;
CDS_LIB"logical_power"
HDL_POWER"GND";
"A"6;
%"SCONN288_ADR50017P087CC"
"2","(2475,2325)","0","pure_quanta","I178";
;
PART_NUMBER"DFHST8FS460"
PART_TYPE"SMLF"
MATERIAL"IO"
VALUE"SCONN288_ADR50017-P087CC"
LOCATION"J14"
NEEDS_NO_SIZE"TRUE"
CDS_LMAN_SYM_OUTLINE"-600,1150,600,-1150"
CDS_LIB"pure_quanta"
$SEC"2"
CDS_SEC"2";
"DQS7_A_C||TDQS7_A_C \B"
$PN"178"51;
"DQS6_A_T||TDQS6_A_T"
$PN"168"69;
"DQS8_B_T||TDQS8_B_T"
$PN"283"61;
"DQS8_B_C||TDQS8_B_C \B"
$PN"282"42;
"DQS7_B_T||TDQS7_B_T"
$PN"272"60;
"DQS0_A_C \B"
$PN"12"44;
"DQS0_A_T"
$PN"11"64;
"DQS0_B_C \B"
$PN"105"34;
"DQS0_B_T"
$PN"104"55;
"DQS1_A_C \B"
$PN"23"45;
"DQS1_A_T"
$PN"22"63;
"DQS1_B_C \B"
$PN"116"36;
"DQS1_B_T"
$PN"115"54;
"DQS2_A_C \B"
$PN"34"46;
"DQS2_A_T"
$PN"33"65;
"DQS2_B_C \B"
$PN"127"35;
"DQS2_B_T"
$PN"126"33;
"DQS3_A_C \B"
$PN"45"47;
"DQS3_A_T"
$PN"44"66;
"DQS3_B_C \B"
$PN"138"37;
"DQS3_B_T"
$PN"137"56;
"DQS4_A_C \B"
$PN"56"48;
"DQS4_A_T"
$PN"55"67;
"DQS4_B_C \B"
$PN"238"38;
"DQS4_B_T"
$PN"239"57;
"DQS5_A_C||TDQS5_A_C||DQS5_A_T||TDQS5_A_T \B"
$PN"156"49;
"DQS5_A_T||TDQS5_A_T"
$PN"157"68;
"DQS5_B_C||TDQS5_B_C \B"
$PN"249"39;
"DQS5_B_T||TDQS5_B_T"
$PN"250"58;
"DQS6_A_C||TDQS6_A_C||DQS6_A_T||TDQS6_A_T \B"
$PN"167"50;
"DQS6_B_C||TDQS6_B_C \B"
$PN"260"40;
"DQS6_B_T||TDQS6_B_T"
$PN"261"59;
"DQS7_A_T||TDQS7_A_T"
$PN"179"70;
"DQS7_B_C||TDQS7_B_C \B"
$PN"271"41;
"DQS8_A_C||TDQS8_A_C \B"
$PN"189"52;
"DQS8_A_T||TDQS8_A_T"
$PN"190"71;
"DQS9_A_C||TDQS9_A_C \B"
$PN"200"53;
"DQS9_A_T||TDQS9_A_T"
$PN"201"72;
"DQS9_B_C||TDQS9_B_C \B"
$PN"94"43;
"DQS9_B_T||TDQS9_B_T||DBI4_B_N"
$PN"93"62;
%"Q_RES"
"1","(-2025,625)","0","pure_quanta","I179";
;
PART_NUMBER"CS04992FB07"
VALUE"49.9"
MATERIAL"CHIP"
$LOCATION"R3888"
CDS_LIB"pure_quanta"
PACK_TYPE"0402LF"
TOLERANCE"1%"
WATTAGE"1/16W"
CDS_LOCATION"R3888"
$SEC"1"
CDS_SEC"1";
"B"
$PN"2"25;
"A"
$PN"1"24;
%"VCC_CORE"
"1","(-1875,1200)","0","logical_power","I21";
;
HDL_POWER"P3V3_AUX"
CDS_LIB"logical_power";
"A"1;
%"TAP"
"1","(-1050,1175)","2","standard","I22";
;
CDS_LIB"standard"
BODY_TYPE"PLUMBING"
HDL_TAP"TRUE";
"B \NAC \NWC"12;
"S \NAC"
BN"1"148;
%"TAP"
"1","(-1050,1125)","2","standard","I23";
;
CDS_LIB"standard"
BODY_TYPE"PLUMBING"
HDL_TAP"TRUE";
"B \NAC \NWC"12;
"S \NAC"
BN"0"147;
%"TAP"
"1","(-1050,1225)","2","standard","I24";
;
CDS_LIB"standard"
BODY_TYPE"PLUMBING"
HDL_TAP"TRUE";
"B \NAC \NWC"12;
"S \NAC"
BN"2"149;
%"TAP"
"1","(-1050,1275)","2","standard","I25";
;
CDS_LIB"standard"
BODY_TYPE"PLUMBING"
HDL_TAP"TRUE";
"B \NAC \NWC"12;
"S \NAC"
BN"3"150;
%"TAP"
"1","(-1050,1325)","2","standard","I26";
;
CDS_LIB"standard"
BODY_TYPE"PLUMBING"
HDL_TAP"TRUE";
"B \NAC \NWC"12;
"S \NAC"
BN"4"151;
%"TAP"
"1","(-1050,1375)","2","standard","I27";
;
CDS_LIB"standard"
BODY_TYPE"PLUMBING"
HDL_TAP"TRUE";
"B \NAC \NWC"12;
"S \NAC"
BN"5"152;
%"TAP"
"1","(-1050,1425)","2","standard","I28";
;
CDS_LIB"standard"
BODY_TYPE"PLUMBING"
HDL_TAP"TRUE";
"B \NAC \NWC"12;
"S \NAC"
BN"6"153;
%"TAP"
"1","(-1050,1575)","2","standard","I29";
;
CDS_LIB"standard"
BODY_TYPE"PLUMBING"
HDL_TAP"TRUE";
"B \NAC \NWC"11;
"S \NAC"
BN"0"154;
%"TAP"
"1","(-1050,1475)","2","standard","I30";
;
CDS_LIB"standard"
BODY_TYPE"PLUMBING"
HDL_TAP"TRUE";
"B \NAC \NWC"12;
"S \NAC"
BN"7"173;
%"TAP"
"1","(-1050,1675)","2","standard","I31";
;
CDS_LIB"standard"
BODY_TYPE"PLUMBING"
HDL_TAP"TRUE";
"B \NAC \NWC"11;
"S \NAC"
BN"2"155;
%"TAP"
"1","(-1050,1625)","2","standard","I32";
;
CDS_LIB"standard"
BODY_TYPE"PLUMBING"
HDL_TAP"TRUE";
"B \NAC \NWC"11;
"S \NAC"
BN"1"174;
%"TAP"
"1","(-1050,1725)","2","standard","I33";
;
CDS_LIB"standard"
BODY_TYPE"PLUMBING"
HDL_TAP"TRUE";
"B \NAC \NWC"11;
"S \NAC"
BN"3"156;
%"TAP"
"1","(-1050,1775)","2","standard","I34";
;
CDS_LIB"standard"
BODY_TYPE"PLUMBING"
HDL_TAP"TRUE";
"B \NAC \NWC"11;
"S \NAC"
BN"4"175;
%"TAP"
"1","(-1050,1825)","2","standard","I35";
;
CDS_LIB"standard"
BODY_TYPE"PLUMBING"
HDL_TAP"TRUE";
"B \NAC \NWC"11;
"S \NAC"
BN"5"157;
%"TAP"
"1","(-1050,1925)","2","standard","I36";
;
CDS_LIB"standard"
BODY_TYPE"PLUMBING"
HDL_TAP"TRUE";
"B \NAC \NWC"11;
"S \NAC"
BN"7"176;
%"TAP"
"1","(-1050,1875)","2","standard","I37";
;
CDS_LIB"standard"
BODY_TYPE"PLUMBING"
HDL_TAP"TRUE";
"B \NAC \NWC"11;
"S \NAC"
BN"6"158;
%"TAP"
"1","(-1050,2625)","2","standard","I38";
;
CDS_LIB"standard"
BODY_TYPE"PLUMBING"
HDL_TAP"TRUE";
"B \NAC \NWC"14;
"S \NAC"
BN"0"171;
%"TAP"
"1","(-1050,2675)","2","standard","I39";
;
CDS_LIB"standard"
BODY_TYPE"PLUMBING"
HDL_TAP"TRUE";
"B \NAC \NWC"14;
"S \NAC"
BN"1"169;
%"TAP"
"1","(-1050,2725)","2","standard","I40";
;
CDS_LIB"standard"
BODY_TYPE"PLUMBING"
HDL_TAP"TRUE";
"B \NAC \NWC"14;
"S \NAC"
BN"2"167;
%"TAP"
"1","(-1050,2775)","2","standard","I41";
;
CDS_LIB"standard"
BODY_TYPE"PLUMBING"
HDL_TAP"TRUE";
"B \NAC \NWC"14;
"S \NAC"
BN"3"165;
%"TAP"
"1","(-1050,2825)","2","standard","I42";
;
CDS_LIB"standard"
BODY_TYPE"PLUMBING"
HDL_TAP"TRUE";
"B \NAC \NWC"14;
"S \NAC"
BN"4"163;
%"TAP"
"1","(-1050,2925)","2","standard","I43";
;
CDS_LIB"standard"
BODY_TYPE"PLUMBING"
HDL_TAP"TRUE";
"B \NAC \NWC"14;
"S \NAC"
BN"6"159;
%"TAP"
"1","(-1050,2875)","2","standard","I44";
;
CDS_LIB"standard"
BODY_TYPE"PLUMBING"
HDL_TAP"TRUE";
"B \NAC \NWC"14;
"S \NAC"
BN"5"161;
%"UNIVERSAL_GND"
"1","(-825,-1050)","0","logical_power","I45";
;
CDS_LIB"logical_power"
HDL_POWER"GND";
"A"5;
%"Q_RES"
"2","(-825,-825)","0","pure_quanta","I46";
;
PART_NUMBER"CS38452FB05"
VALUE"84.5K"
WATTAGE"1/16W"
MATERIAL"CHIP"
TOLERANCE"1%"
PACK_TYPE"0402LF"
$LOCATION"R39"
CDS_LIB"pure_quanta"
CDS_LOCATION"R39"
$SEC"1"
CDS_SEC"1";
"A"
$PN"1"178;
"B"
$PN"2"5;
%"SCONN288_ADR50017P087CC"
"1","(-225,1600)","0","pure_quanta","I47";
;
PART_NUMBER"DFHST8FS460"
MATERIAL"IO"
PART_TYPE"SMLF"
VALUE"SCONN288_ADR50017-P087CC"
$LOCATION"J14"
NEEDS_NO_SIZE"TRUE"
CDS_LMAN_SYM_OUTLINE"-450,1875,450,-1875"
CDS_LIB"pure_quanta"
CDS_LOCATION"J14"
$SEC"1"
CDS_SEC"1";
"DQ31_A"
$PN"194"177;
"CB7_A"
$PN"205"176;
"CB4_A"
$PN"58"175;
"CB1_A"
$PN"53"174;
"CB7_B"
$PN"236"173;
"ALERT_N \B"
$PN"62"22;
"CA0_A"
$PN"66"172;
"CA0_B"
$PN"76"171;
"CA1_A"
$PN"211"170;
"CA1_B"
$PN"221"169;
"CA2_A"
$PN"68"168;
"CA2_B"
$PN"78"167;
"CA3_A"
$PN"213"166;
"CA3_B"
$PN"223"165;
"CA4_A"
$PN"70"164;
"CA4_B"
$PN"80"163;
"CA5_A"
$PN"215"162;
"CA5_B"
$PN"225"161;
"CA6_A"
$PN"72"160;
"CA6_B"
$PN"82"159;
"CB6_A"
$PN"203"158;
"CB5_A"
$PN"60"157;
"CB3_A"
$PN"198"156;
"CB2_A"
$PN"196"155;
"CB0_A"
$PN"51"154;
"CB6_B"
$PN"234"153;
"CB5_B"
$PN"91"152;
"CB4_B"
$PN"89"151;
"CB3_B"
$PN"243"150;
"CB2_B"
$PN"241"149;
"CB1_B"
$PN"98"148;
"CB0_B"
$PN"96"147;
"CK_C \B"
$PN"218"146;
"CK_T"
$PN"217"145;
"CS0_A_N"
$PN"64"144;
"CS0_B_N"
$PN"84"143;
"CS1_A_N"
$PN"209"142;
"CS1_B_N"
$PN"229"141;
"DQ30_A"
$PN"192"140;
"DQ29_A"
$PN"49"139;
"DQ28_A"
$PN"47"138;
"DQ27_A"
$PN"187"137;
"DQ26_A"
$PN"185"136;
"DQ25_A"
$PN"42"135;
"DQ24_A"
$PN"40"134;
"DQ23_A"
$PN"183"133;
"DQ22_A"
$PN"181"132;
"DQ21_A"
$PN"38"76;
"DQ20_A"
$PN"36"131;
"DQ19_A"
$PN"176"130;
"DQ18_A"
$PN"174"129;
"DQ17_A"
$PN"31"128;
"DQ16_A"
$PN"29"74;
"DQ15_A"
$PN"172"127;
"DQ14_A"
$PN"170"75;
"DQ13_A"
$PN"27"126;
"DQ12_A"
$PN"25"125;
"DQ11_A"
$PN"165"124;
"DQ10_A"
$PN"163"123;
"DQ9_A"
$PN"20"122;
"DQ8_A"
$PN"18"121;
"DQ7_A"
$PN"161"120;
"DQ6_A"
$PN"159"119;
"DQ5_A"
$PN"16"118;
"DQ4_A"
$PN"14"117;
"DQ3_A"
$PN"154"116;
"DQ2_A"
$PN"152"115;
"DQ1_A"
$PN"9"114;
"DQ0_A"
$PN"7"113;
"DQ31_B"
$PN"287"112;
"DQ30_B"
$PN"285"111;
"DQ29_B"
$PN"142"110;
"DQ28_B"
$PN"140"77;
"DQ27_B"
$PN"280"109;
"DQ26_B"
$PN"278"108;
"DQ25_B"
$PN"135"107;
"DQ24_B"
$PN"133"106;
"DQ23_B"
$PN"276"105;
"DQ22_B"
$PN"274"104;
"DQ21_B"
$PN"131"103;
"DQ20_B"
$PN"129"102;
"DQ19_B"
$PN"269"101;
"DQ18_B"
$PN"267"100;
"DQ17_B"
$PN"124"99;
"DQ16_B"
$PN"122"98;
"DQ15_B"
$PN"265"78;
"DQ14_B"
$PN"263"97;
"DQ13_B"
$PN"120"96;
"DQ12_B"
$PN"118"95;
"DQ11_B"
$PN"258"94;
"DQ10_B"
$PN"256"93;
"DQ9_B"
$PN"113"92;
"DQ8_B"
$PN"111"91;
"DQ7_B"
$PN"254"90;
"DQ6_B"
$PN"252"89;
"DQ5_B"
$PN"109"88;
"DQ4_B"
$PN"107"87;
"DQ3_B"
$PN"247"86;
"DQ2_B"
$PN"245"85;
"DQ1_B"
$PN"102"84;
"DQ0_B"
$PN"100"83;
"HSA"
$PN"148"20;
"HSCL"
$PN"4"24;
"HSDA"
$PN"5"21;
"LBD||RSP_A_N"
$PN"86"82;
"LBS||RSP_B_N"
$PN"87"81;
"PAR_A"
$PN"74"80;
"PAR_B"
$PN"227"79;
"PWR_GOOD||FAIL_N"
$PN"147"26;
"RESET_N \B"
$PN"207"23;
"RFU6"
$PN"232"73;
"RFU5"
$PN"231"30;
"RFU4"
$PN"220"27;
"RFU3"
$PN"150"28;
"RFU2"
$PN"149"31;
"RFU1"
$PN"144"32;
"RFU0"
$PN"2"29;
"VIN_MGMT"
$PN"3"1;
%"TAP"
"1","(600,175)","0","standard","I48";
;
CDS_LIB"standard"
BODY_TYPE"PLUMBING"
HDL_TAP"TRUE";
"B \NAC \NWC"15;
"S \NAC"
BN"1"84;
%"TAP"
"1","(600,125)","0","standard","I49";
;
CDS_LIB"standard"
BODY_TYPE"PLUMBING"
HDL_TAP"TRUE";
"B \NAC \NWC"15;
"S \NAC"
BN"0"83;
%"TAP"
"1","(600,225)","0","standard","I50";
;
CDS_LIB"standard"
BODY_TYPE"PLUMBING"
HDL_TAP"TRUE";
"B \NAC \NWC"15;
"S \NAC"
BN"2"85;
%"TAP"
"1","(600,275)","0","standard","I51";
;
CDS_LIB"standard"
BODY_TYPE"PLUMBING"
HDL_TAP"TRUE";
"B \NAC \NWC"15;
"S \NAC"
BN"3"86;
%"TAP"
"1","(600,425)","0","standard","I52";
;
CDS_LIB"standard"
BODY_TYPE"PLUMBING"
HDL_TAP"TRUE";
"B \NAC \NWC"15;
"S \NAC"
BN"6"89;
%"TAP"
"1","(600,375)","0","standard","I53";
;
CDS_LIB"standard"
BODY_TYPE"PLUMBING"
HDL_TAP"TRUE";
"B \NAC \NWC"15;
"S \NAC"
BN"5"88;
%"TAP"
"1","(600,325)","0","standard","I54";
;
CDS_LIB"standard"
BODY_TYPE"PLUMBING"
HDL_TAP"TRUE";
"B \NAC \NWC"15;
"S \NAC"
BN"4"87;
%"TAP"
"1","(600,525)","0","standard","I55";
;
CDS_LIB"standard"
BODY_TYPE"PLUMBING"
HDL_TAP"TRUE";
"B \NAC \NWC"15;
"S \NAC"
BN"8"91;
%"TAP"
"1","(600,475)","0","standard","I56";
;
CDS_LIB"standard"
BODY_TYPE"PLUMBING"
HDL_TAP"TRUE";
"B \NAC \NWC"15;
"S \NAC"
BN"7"90;
%"TAP"
"1","(600,575)","0","standard","I57";
;
CDS_LIB"standard"
BODY_TYPE"PLUMBING"
HDL_TAP"TRUE";
"B \NAC \NWC"15;
"S \NAC"
BN"9"92;
%"TAP"
"1","(600,625)","0","standard","I58";
;
CDS_LIB"standard"
BODY_TYPE"PLUMBING"
HDL_TAP"TRUE";
"B \NAC \NWC"15;
"S \NAC"
BN"10"93;
%"TAP"
"1","(600,675)","0","standard","I59";
;
CDS_LIB"standard"
BODY_TYPE"PLUMBING"
HDL_TAP"TRUE";
"B \NAC \NWC"15;
"S \NAC"
BN"11"94;
%"TAP"
"1","(600,775)","0","standard","I60";
;
CDS_LIB"standard"
BODY_TYPE"PLUMBING"
HDL_TAP"TRUE";
"B \NAC \NWC"15;
"S \NAC"
BN"13"96;
%"TAP"
"1","(600,725)","0","standard","I61";
;
CDS_LIB"standard"
BODY_TYPE"PLUMBING"
HDL_TAP"TRUE";
"B \NAC \NWC"15;
"S \NAC"
BN"12"95;
%"TAP"
"1","(600,825)","0","standard","I62";
;
CDS_LIB"standard"
BODY_TYPE"PLUMBING"
HDL_TAP"TRUE";
"B \NAC \NWC"15;
"S \NAC"
BN"14"97;
%"TAP"
"1","(600,875)","0","standard","I63";
;
CDS_LIB"standard"
BODY_TYPE"PLUMBING"
HDL_TAP"TRUE";
"B \NAC \NWC"15;
"S \NAC"
BN"15"78;
%"TAP"
"1","(600,925)","0","standard","I64";
;
CDS_LIB"standard"
BODY_TYPE"PLUMBING"
HDL_TAP"TRUE";
"B \NAC \NWC"15;
"S \NAC"
BN"16"98;
%"TAP"
"1","(600,1075)","0","standard","I65";
;
CDS_LIB"standard"
BODY_TYPE"PLUMBING"
HDL_TAP"TRUE";
"B \NAC \NWC"15;
"S \NAC"
BN"19"101;
%"TAP"
"1","(600,1025)","0","standard","I66";
;
CDS_LIB"standard"
BODY_TYPE"PLUMBING"
HDL_TAP"TRUE";
"B \NAC \NWC"15;
"S \NAC"
BN"18"100;
%"TAP"
"1","(600,975)","0","standard","I67";
;
CDS_LIB"standard"
BODY_TYPE"PLUMBING"
HDL_TAP"TRUE";
"B \NAC \NWC"15;
"S \NAC"
BN"17"99;
%"TAP"
"1","(600,1175)","0","standard","I68";
;
CDS_LIB"standard"
BODY_TYPE"PLUMBING"
HDL_TAP"TRUE";
"B \NAC \NWC"15;
"S \NAC"
BN"21"103;
%"TAP"
"1","(600,1125)","0","standard","I69";
;
CDS_LIB"standard"
BODY_TYPE"PLUMBING"
HDL_TAP"TRUE";
"B \NAC \NWC"15;
"S \NAC"
BN"20"102;
%"TAP"
"1","(600,1325)","0","standard","I70";
;
CDS_LIB"standard"
BODY_TYPE"PLUMBING"
HDL_TAP"TRUE";
"B \NAC \NWC"15;
"S \NAC"
BN"24"106;
%"TAP"
"1","(600,1275)","0","standard","I71";
;
CDS_LIB"standard"
BODY_TYPE"PLUMBING"
HDL_TAP"TRUE";
"B \NAC \NWC"15;
"S \NAC"
BN"23"105;
%"TAP"
"1","(600,1225)","0","standard","I72";
;
CDS_LIB"standard"
BODY_TYPE"PLUMBING"
HDL_TAP"TRUE";
"B \NAC \NWC"15;
"S \NAC"
BN"22"104;
%"TAP"
"1","(600,1375)","0","standard","I73";
;
CDS_LIB"standard"
BODY_TYPE"PLUMBING"
HDL_TAP"TRUE";
"B \NAC \NWC"15;
"S \NAC"
BN"25"107;
%"TAP"
"1","(600,1425)","0","standard","I74";
;
CDS_LIB"standard"
BODY_TYPE"PLUMBING"
HDL_TAP"TRUE";
"B \NAC \NWC"15;
"S \NAC"
BN"26"108;
%"TAP"
"1","(600,1575)","0","standard","I75";
;
CDS_LIB"standard"
BODY_TYPE"PLUMBING"
HDL_TAP"TRUE";
"B \NAC \NWC"15;
"S \NAC"
BN"29"110;
%"TAP"
"1","(600,1525)","0","standard","I76";
;
CDS_LIB"standard"
BODY_TYPE"PLUMBING"
HDL_TAP"TRUE";
"B \NAC \NWC"15;
"S \NAC"
BN"28"77;
%"TAP"
"1","(600,1475)","0","standard","I77";
;
CDS_LIB"standard"
BODY_TYPE"PLUMBING"
HDL_TAP"TRUE";
"B \NAC \NWC"15;
"S \NAC"
BN"27"109;
%"TAP"
"1","(600,1625)","0","standard","I78";
;
CDS_LIB"standard"
BODY_TYPE"PLUMBING"
HDL_TAP"TRUE";
"B \NAC \NWC"15;
"S \NAC"
BN"30"111;
%"TAP"
"1","(600,1675)","0","standard","I79";
;
CDS_LIB"standard"
BODY_TYPE"PLUMBING"
HDL_TAP"TRUE";
"B \NAC \NWC"15;
"S \NAC"
BN"31"112;
%"TAP"
"1","(600,1775)","0","standard","I80";
;
CDS_LIB"standard"
BODY_TYPE"PLUMBING"
HDL_TAP"TRUE";
"B \NAC \NWC"10;
"S \NAC"
BN"0"113;
%"TAP"
"1","(600,1825)","0","standard","I81";
;
CDS_LIB"standard"
BODY_TYPE"PLUMBING"
HDL_TAP"TRUE";
"B \NAC \NWC"10;
"S \NAC"
BN"1"114;
%"TAP"
"1","(600,1925)","0","standard","I82";
;
CDS_LIB"standard"
BODY_TYPE"PLUMBING"
HDL_TAP"TRUE";
"B \NAC \NWC"10;
"S \NAC"
BN"3"116;
%"TAP"
"1","(600,1875)","0","standard","I83";
;
CDS_LIB"standard"
BODY_TYPE"PLUMBING"
HDL_TAP"TRUE";
"B \NAC \NWC"10;
"S \NAC"
BN"2"115;
%"TAP"
"1","(600,1975)","0","standard","I84";
;
CDS_LIB"standard"
BODY_TYPE"PLUMBING"
HDL_TAP"TRUE";
"B \NAC \NWC"10;
"S \NAC"
BN"4"117;
%"TAP"
"1","(600,2025)","0","standard","I85";
;
CDS_LIB"standard"
BODY_TYPE"PLUMBING"
HDL_TAP"TRUE";
"B \NAC \NWC"10;
"S \NAC"
BN"5"118;
%"TAP"
"1","(600,2075)","0","standard","I86";
;
CDS_LIB"standard"
BODY_TYPE"PLUMBING"
HDL_TAP"TRUE";
"B \NAC \NWC"10;
"S \NAC"
BN"6"119;
%"TAP"
"1","(600,2125)","0","standard","I87";
;
CDS_LIB"standard"
BODY_TYPE"PLUMBING"
HDL_TAP"TRUE";
"B \NAC \NWC"10;
"S \NAC"
BN"7"120;
%"TAP"
"1","(600,2175)","0","standard","I88";
;
CDS_LIB"standard"
BODY_TYPE"PLUMBING"
HDL_TAP"TRUE";
"B \NAC \NWC"10;
"S \NAC"
BN"8"121;
%"TAP"
"1","(600,2225)","0","standard","I89";
;
CDS_LIB"standard"
BODY_TYPE"PLUMBING"
HDL_TAP"TRUE";
"B \NAC \NWC"10;
"S \NAC"
BN"9"122;
%"TAP"
"1","(600,2275)","0","standard","I90";
;
CDS_LIB"standard"
BODY_TYPE"PLUMBING"
HDL_TAP"TRUE";
"B \NAC \NWC"10;
"S \NAC"
BN"10"123;
%"TAP"
"1","(600,2325)","0","standard","I91";
;
CDS_LIB"standard"
BODY_TYPE"PLUMBING"
HDL_TAP"TRUE";
"B \NAC \NWC"10;
"S \NAC"
BN"11"124;
%"TAP"
"1","(600,2375)","0","standard","I92";
;
CDS_LIB"standard"
BODY_TYPE"PLUMBING"
HDL_TAP"TRUE";
"B \NAC \NWC"10;
"S \NAC"
BN"12"125;
%"TAP"
"1","(600,2475)","0","standard","I93";
;
CDS_LIB"standard"
BODY_TYPE"PLUMBING"
HDL_TAP"TRUE";
"B \NAC \NWC"10;
"S \NAC"
BN"14"75;
%"TAP"
"1","(600,2425)","0","standard","I94";
;
CDS_LIB"standard"
BODY_TYPE"PLUMBING"
HDL_TAP"TRUE";
"B \NAC \NWC"10;
"S \NAC"
BN"13"126;
%"TAP"
"1","(600,2575)","0","standard","I95";
;
CDS_LIB"standard"
BODY_TYPE"PLUMBING"
HDL_TAP"TRUE";
"B \NAC \NWC"10;
"S \NAC"
BN"16"74;
%"TAP"
"1","(600,2525)","0","standard","I96";
;
CDS_LIB"standard"
BODY_TYPE"PLUMBING"
HDL_TAP"TRUE";
"B \NAC \NWC"10;
"S \NAC"
BN"15"127;
%"TAP"
"1","(600,2725)","0","standard","I97";
;
CDS_LIB"standard"
BODY_TYPE"PLUMBING"
HDL_TAP"TRUE";
"B \NAC \NWC"10;
"S \NAC"
BN"19"130;
%"TAP"
"1","(600,2675)","0","standard","I98";
;
CDS_LIB"standard"
BODY_TYPE"PLUMBING"
HDL_TAP"TRUE";
"B \NAC \NWC"10;
"S \NAC"
BN"18"129;
%"TAP"
"1","(600,2625)","0","standard","I99";
;
CDS_LIB"standard"
BODY_TYPE"PLUMBING"
HDL_TAP"TRUE";
"B \NAC \NWC"10;
"S \NAC"
BN"17"128;
END.
